(kicad_pcb
	(version 20260206)
	(generator "pcbnew")
	(generator_version "10.0")
	(general
		(thickness 1.6)
		(legacy_teardrops no)
	)
	(paper "A4")
	(title_block
		(title "m-2 — Lightning_M.2_BRD.brd")
		(comment 1 "Lightning (Wiwynn / Facebook NVMe JBOF) / footprints 25-31 of 157")
	)
	(layers
		(0 "F.Cu" signal "TOP")
		(4 "In1.Cu" signal "L2GND")
		(6 "In2.Cu" signal "L3")
		(8 "In3.Cu" signal "L4GND")
		(10 "In4.Cu" signal "L5GND")
		(12 "In5.Cu" signal "L6")
		(14 "In6.Cu" signal "L7GND")
		(2 "B.Cu" signal "BOTTOM")
		(9 "F.Adhes" user "F.Adhesive")
		(11 "B.Adhes" user "B.Adhesive")
		(13 "F.Paste" user "Package Geometry/Pastemask Top")
		(15 "B.Paste" user "Package Geometry/Pastemask Bottom")
		(5 "F.SilkS" user "Ref Des/Silkscreen Top")
		(7 "B.SilkS" user "Ref Des/Silkscreen Bottom")
		(1 "F.Mask" user "Board Geometry/Soldermask Top")
		(3 "B.Mask" user "Board Geometry/Soldermask Bottom")
		(17 "Dwgs.User" user "User.Drawings")
		(19 "Cmts.User" user "User.Comments")
		(21 "Eco1.User" user "User.Eco1")
		(23 "Eco2.User" user "User.Eco2")
		(25 "Edge.Cuts" user "Board Geometry/Outline")
		(27 "Margin" user)
		(31 "F.CrtYd" user "Package Geometry/Place Bound Top")
		(29 "B.CrtYd" user "Package Geometry/Place Bound Bottom")
		(35 "F.Fab" user "Ref Des/Assembly Top")
		(33 "B.Fab" user "Ref Des/Assembly Bottom")
	)
	(footprint ""
		(layer "F.Cu")
		(at 15.748 -84.122006 -90)
		(property "Reference" "PC26"
			(at 0 0 270)
			(layer "F.SilkS")
			(hide yes)
			(effects
				(font
					(size 1.27 1.27)
				)
			)
		)
		(property "Value" "SC10U6D3V5KX-4GP"
			(at -0.0762 -6.1214 270)
			(unlocked yes)
			(layer "F.Fab")
			(hide yes)
			(effects
				(font
					(size 1.016 1.016)
					(thickness 0.1524)
				)
			)
		)
		(property "Device Type" "C805H58"
			(at -0.0762 -8.1534 270)
			(unlocked yes)
			(layer "F.Fab")
			(hide yes)
			(effects
				(font
					(size 1.016 1.016)
					(thickness 0.1524)
				)
			)
		)
		(duplicate_pad_numbers_are_jumpers no)
		(fp_line
			(start 0.635 0)
			(end -0.635 0)
			(stroke
				(width 0.508)
				(type default)
			)
			(layer "F.SilkS")
		)
		(fp_rect
			(start -0.9652 1.778)
			(end 0.9652 -1.778)
			(stroke
				(width 0)
				(type default)
			)
			(fill no)
			(layer "F.CrtYd")
		)
		(fp_poly
			(pts
				(xy -0.9652 -1.778) (xy 0.9652 -1.778) (xy 0.9652 1.778) (xy -0.9652 1.778)
			)
			(stroke
				(width 0)
				(type default)
			)
			(fill no)
			(layer "F.Fab")
		)
		(pad "1" smd rect
			(at 0 -0.9652 270)
			(size 1.397 1.143)
			(layers "F.Cu" "F.Mask" "F.Paste")
			(net "P1V8_PWR_BIAS")
		)
		(pad "2" smd rect
			(at 0 0.9652 270)
			(size 1.397 1.143)
			(layers "F.Cu" "F.Mask" "F.Paste")
			(net "GND")
		)
	)
	(footprint ""
		(layer "F.Cu")
		(at 33.02 -74.549)
		(property "Reference" "C11"
			(at 0 0 0)
			(layer "F.SilkS")
			(hide yes)
			(effects
				(font
					(size 1.27 1.27)
				)
			)
		)
		(property "Value" "SCD1U16V2KX-3GP"
			(at 1.1811 -2.7051 0)
			(unlocked yes)
			(layer "F.Fab")
			(hide yes)
			(effects
				(font
					(size 1.016 1.016)
					(thickness 0.1524)
				)
			)
		)
		(property "Device Type" "C402H22"
			(at 1.1811 -4.2291 0)
			(unlocked yes)
			(layer "F.Fab")
			(hide yes)
			(effects
				(font
					(size 1.016 1.016)
					(thickness 0.1524)
				)
			)
		)
		(duplicate_pad_numbers_are_jumpers no)
		(fp_rect
			(start -0.4318 0.9525)
			(end 0.4318 -0.9525)
			(stroke
				(width 0)
				(type default)
			)
			(fill no)
			(layer "F.CrtYd")
		)
		(fp_rect
			(start -0.4318 0.9525)
			(end 0.4318 -0.9525)
			(stroke
				(width 0)
				(type default)
			)
			(fill no)
			(layer "F.Fab")
		)
		(pad "1" smd custom
			(at 0 -0.4445)
			(size 0.1524 0.1524)
			(layers "F.Cu" "F.Mask" "F.Paste")
			(net "P3V3_DPB")
			(options
				(clearance outline)
				(anchor circle)
			)
			(primitives
				(gr_poly
					(pts
						(arc
							(start 0.3048 -0.2032)
							(mid 0.275042 -0.275042)
							(end 0.2032 -0.3048)
						)
						(arc
							(start -0.2032 -0.3048)
							(mid -0.275042 -0.275042)
							(end -0.3048 -0.2032)
						)
						(arc
							(start -0.3048 0.2032)
							(mid -0.275042 0.275042)
							(end -0.2032 0.3048)
						)
						(arc
							(start 0.2032 0.3048)
							(mid 0.275042 0.275042)
							(end 0.3048 0.2032)
						)
					)
					(width 0)
					(fill yes)
				)
			)
		)
		(pad "2" smd custom
			(at 0 0.4445)
			(size 0.1524 0.1524)
			(layers "F.Cu" "F.Mask" "F.Paste")
			(net "GND")
			(options
				(clearance outline)
				(anchor circle)
			)
			(primitives
				(gr_poly
					(pts
						(arc
							(start 0.3048 -0.2032)
							(mid 0.275042 -0.275042)
							(end 0.2032 -0.3048)
						)
						(arc
							(start -0.2032 -0.3048)
							(mid -0.275042 -0.275042)
							(end -0.3048 -0.2032)
						)
						(arc
							(start -0.3048 0.2032)
							(mid -0.275042 0.275042)
							(end -0.2032 0.3048)
						)
						(arc
							(start 0.2032 0.3048)
							(mid 0.275042 0.275042)
							(end 0.3048 0.2032)
						)
					)
					(width 0)
					(fill yes)
				)
			)
		)
	)
	(footprint ""
		(layer "F.Cu")
		(at 30.226 -78.74)
		(property "Reference" "R39"
			(at 0 0 0)
			(layer "F.SilkS")
			(hide yes)
			(effects
				(font
					(size 1.27 1.27)
				)
			)
		)
		(property "Value" "0R2J-2-GP"
			(at 0.064008 -3.993896 0)
			(unlocked yes)
			(layer "F.Fab")
			(hide yes)
			(effects
				(font
					(size 1.016 1.016)
					(thickness 0.1524)
				)
			)
		)
		(property "Device Type" "R402H16"
			(at 0.064008 -5.517896 0)
			(unlocked yes)
			(layer "F.Fab")
			(hide yes)
			(effects
				(font
					(size 1.016 1.016)
					(thickness 0.1524)
				)
			)
		)
		(duplicate_pad_numbers_are_jumpers no)
		(fp_line
			(start -0.508 -0.9398)
			(end -0.508 0.9398)
			(stroke
				(width 0.1524)
				(type default)
			)
			(layer "F.SilkS")
		)
		(fp_line
			(start 0.508 -0.9398)
			(end -0.508 -0.9398)
			(stroke
				(width 0.1524)
				(type default)
			)
			(layer "F.SilkS")
		)
		(fp_rect
			(start -0.508 0.9398)
			(end 0.508 -0.9398)
			(stroke
				(width 0)
				(type default)
			)
			(fill no)
			(layer "F.CrtYd")
		)
		(fp_rect
			(start -0.508 0.9398)
			(end 0.508 -0.9398)
			(stroke
				(width 0)
				(type default)
			)
			(fill no)
			(layer "F.Fab")
		)
		(pad "1" smd custom
			(at 0 -0.4445)
			(size 0.1397 0.1397)
			(layers "F.Cu" "F.Mask" "F.Paste")
			(net "Z50_SSD_A1_SMB_CLK_R")
			(options
				(clearance outline)
				(anchor circle)
			)
			(primitives
				(gr_poly
					(pts
						(arc
							(start -0.1778 -0.2794)
							(mid -0.249642 -0.249642)
							(end -0.2794 -0.1778)
						)
						(arc
							(start -0.2794 0.1778)
							(mid -0.249642 0.249642)
							(end -0.1778 0.2794)
						)
						(arc
							(start 0.1778 0.2794)
							(mid 0.249642 0.249642)
							(end 0.2794 0.1778)
						)
						(arc
							(start 0.2794 -0.1778)
							(mid 0.249642 -0.249642)
							(end 0.1778 -0.2794)
						)
					)
					(width 0)
					(fill yes)
				)
			)
		)
		(pad "2" smd custom
			(at 0 0.4445)
			(size 0.1397 0.1397)
			(layers "F.Cu" "F.Mask" "F.Paste")
			(net "Z50_SSD_A1_SMB_CLK_LL")
			(options
				(clearance outline)
				(anchor circle)
			)
			(primitives
				(gr_poly
					(pts
						(arc
							(start -0.1778 -0.2794)
							(mid -0.249642 -0.249642)
							(end -0.2794 -0.1778)
						)
						(arc
							(start -0.2794 0.1778)
							(mid -0.249642 0.249642)
							(end -0.1778 0.2794)
						)
						(arc
							(start 0.1778 0.2794)
							(mid 0.249642 0.249642)
							(end 0.2794 0.1778)
						)
						(arc
							(start 0.2794 -0.1778)
							(mid 0.249642 -0.249642)
							(end 0.1778 -0.2794)
						)
					)
					(width 0)
					(fill yes)
				)
			)
		)
	)
	(footprint ""
		(layer "F.Cu")
		(at 27.813 -72.39)
		(property "Reference" "C9"
			(at 0 0 0)
			(layer "F.SilkS")
			(hide yes)
			(effects
				(font
					(size 1.27 1.27)
				)
			)
		)
		(property "Value" "SCD1U16V2KX-3GP"
			(at 1.1811 -2.7051 0)
			(unlocked yes)
			(layer "F.Fab")
			(hide yes)
			(effects
				(font
					(size 1.016 1.016)
					(thickness 0.1524)
				)
			)
		)
		(property "Device Type" "C402H22"
			(at 1.1811 -4.2291 0)
			(unlocked yes)
			(layer "F.Fab")
			(hide yes)
			(effects
				(font
					(size 1.016 1.016)
					(thickness 0.1524)
				)
			)
		)
		(duplicate_pad_numbers_are_jumpers no)
		(fp_rect
			(start -0.4318 0.9525)
			(end 0.4318 -0.9525)
			(stroke
				(width 0)
				(type default)
			)
			(fill no)
			(layer "F.CrtYd")
		)
		(fp_rect
			(start -0.4318 0.9525)
			(end 0.4318 -0.9525)
			(stroke
				(width 0)
				(type default)
			)
			(fill no)
			(layer "F.Fab")
		)
		(pad "1" smd custom
			(at 0 -0.4445)
			(size 0.1524 0.1524)
			(layers "F.Cu" "F.Mask" "F.Paste")
			(net "P1V8_PWR")
			(options
				(clearance outline)
				(anchor circle)
			)
			(primitives
				(gr_poly
					(pts
						(arc
							(start 0.3048 -0.2032)
							(mid 0.275042 -0.275042)
							(end 0.2032 -0.3048)
						)
						(arc
							(start -0.2032 -0.3048)
							(mid -0.275042 -0.275042)
							(end -0.3048 -0.2032)
						)
						(arc
							(start -0.3048 0.2032)
							(mid -0.275042 0.275042)
							(end -0.2032 0.3048)
						)
						(arc
							(start 0.2032 0.3048)
							(mid 0.275042 0.275042)
							(end 0.3048 0.2032)
						)
					)
					(width 0)
					(fill yes)
				)
			)
		)
		(pad "2" smd custom
			(at 0 0.4445)
			(size 0.1524 0.1524)
			(layers "F.Cu" "F.Mask" "F.Paste")
			(net "GND")
			(options
				(clearance outline)
				(anchor circle)
			)
			(primitives
				(gr_poly
					(pts
						(arc
							(start 0.3048 -0.2032)
							(mid 0.275042 -0.275042)
							(end 0.2032 -0.3048)
						)
						(arc
							(start -0.2032 -0.3048)
							(mid -0.275042 -0.275042)
							(end -0.3048 -0.2032)
						)
						(arc
							(start -0.3048 0.2032)
							(mid -0.275042 0.275042)
							(end -0.2032 0.3048)
						)
						(arc
							(start 0.2032 0.3048)
							(mid 0.275042 0.275042)
							(end 0.3048 0.2032)
						)
					)
					(width 0)
					(fill yes)
				)
			)
		)
	)
	(footprint ""
		(layer "F.Cu")
		(at 59.817 -30.988 -90)
		(property "Reference" "C38"
			(at 0 0 270)
			(layer "F.SilkS")
			(hide yes)
			(effects
				(font
					(size 1.27 1.27)
				)
			)
		)
		(property "Value" "SC1U6D3V2KX-9-GP"
			(at 1.1811 -2.7051 270)
			(unlocked yes)
			(layer "F.Fab")
			(hide yes)
			(effects
				(font
					(size 1.016 1.016)
					(thickness 0.1524)
				)
			)
		)
		(property "Device Type" "C402H22"
			(at 1.1811 -4.2291 270)
			(unlocked yes)
			(layer "F.Fab")
			(hide yes)
			(effects
				(font
					(size 1.016 1.016)
					(thickness 0.1524)
				)
			)
		)
		(duplicate_pad_numbers_are_jumpers no)
		(fp_rect
			(start -0.4318 0.9525)
			(end 0.4318 -0.9525)
			(stroke
				(width 0)
				(type default)
			)
			(fill no)
			(layer "F.CrtYd")
		)
		(fp_rect
			(start -0.4318 0.9525)
			(end 0.4318 -0.9525)
			(stroke
				(width 0)
				(type default)
			)
			(fill no)
			(layer "F.Fab")
		)
		(pad "1" smd custom
			(at 0 -0.4445 270)
			(size 0.1524 0.1524)
			(layers "F.Cu" "F.Mask" "F.Paste")
			(net "P3V3_PWR")
			(options
				(clearance outline)
				(anchor circle)
			)
			(primitives
				(gr_poly
					(pts
						(arc
							(start 0.3048 -0.2032)
							(mid 0.275042 -0.275042)
							(end 0.2032 -0.3048)
						)
						(arc
							(start -0.2032 -0.3048)
							(mid -0.275042 -0.275042)
							(end -0.3048 -0.2032)
						)
						(arc
							(start -0.3048 0.2032)
							(mid -0.275042 0.275042)
							(end -0.2032 0.3048)
						)
						(arc
							(start 0.2032 0.3048)
							(mid 0.275042 0.275042)
							(end 0.3048 0.2032)
						)
					)
					(width 0)
					(fill yes)
				)
			)
		)
		(pad "2" smd custom
			(at 0 0.4445 270)
			(size 0.1524 0.1524)
			(layers "F.Cu" "F.Mask" "F.Paste")
			(net "GND")
			(options
				(clearance outline)
				(anchor circle)
			)
			(primitives
				(gr_poly
					(pts
						(arc
							(start 0.3048 -0.2032)
							(mid 0.275042 -0.275042)
							(end 0.2032 -0.3048)
						)
						(arc
							(start -0.2032 -0.3048)
							(mid -0.275042 -0.275042)
							(end -0.3048 -0.2032)
						)
						(arc
							(start -0.3048 0.2032)
							(mid -0.275042 0.275042)
							(end -0.2032 0.3048)
						)
						(arc
							(start 0.2032 0.3048)
							(mid 0.275042 0.275042)
							(end 0.3048 0.2032)
						)
					)
					(width 0)
					(fill yes)
				)
			)
		)
	)
	(footprint ""
		(layer "F.Cu")
		(at 41.226994 -75.819)
		(property "Reference" "TP2"
			(at 0 0 0)
			(layer "F.SilkS")
			(hide yes)
			(effects
				(font
					(size 1.27 1.27)
				)
			)
		)
		(property "Value" "TPAD28-1-GP-U"
			(at 0.0508 -1.9304 0)
			(unlocked yes)
			(layer "F.Fab")
			(hide yes)
			(effects
				(font
					(size 1.016 1.016)
					(thickness 0.1524)
				)
			)
		)
		(property "Device Type" "TPAD28-1-U"
			(at 0.0508 -3.4544 0)
			(unlocked yes)
			(layer "F.Fab")
			(hide yes)
			(effects
				(font
					(size 1.016 1.016)
					(thickness 0.1524)
				)
			)
		)
		(duplicate_pad_numbers_are_jumpers no)
		(fp_poly
			(pts
				(arc
					(start 0.3556 0)
					(mid -0.3556 0)
					(end 0.3556 0)
				)
			)
			(stroke
				(width 0)
				(type default)
			)
			(fill no)
			(layer "F.CrtYd")
		)
		(fp_poly
			(pts
				(arc
					(start 0.9525 0)
					(mid -0.9525 0)
					(end 0.9525 0)
				)
			)
			(stroke
				(width 0)
				(type default)
			)
			(fill no)
			(layer "F.Fab")
		)
		(pad "1" smd circle
			(at 0 0)
			(size 0.7112 0.7112)
			(layers "F.Cu" "F.Mask" "F.Paste")
			(net "P3V3_DEV_PWRGD")
		)
	)
	(footprint ""
		(layer "F.Cu")
		(at 18.161 -80.185006)
		(property "Reference" "PU2"
			(at 0 0 0)
			(layer "F.SilkS")
			(hide yes)
			(effects
				(font
					(size 1.27 1.27)
				)
			)
		)
		(property "Value" "TPS74801DRCR-1-GP-U"
			(at -3.5306 1.3208 0)
			(unlocked yes)
			(layer "F.Fab")
			(hide yes)
			(effects
				(font
					(size 1.016 1.016)
					(thickness 0.1524)
				)
			)
		)
		(property "Device Type" "DFN10G3-G315175H40"
			(at -3.5306 -0.2032 0)
			(unlocked yes)
			(layer "F.Fab")
			(hide yes)
			(effects
				(font
					(size 1.016 1.016)
					(thickness 0.1524)
				)
			)
		)
		(duplicate_pad_numbers_are_jumpers no)
		(fp_line
			(start -2.3876 -2.5146)
			(end -2.3876 -1.7526)
			(stroke
				(width 0.1524)
				(type default)
			)
			(layer "F.SilkS")
		)
		(fp_line
			(start -2.3876 1.7526)
			(end -2.3876 2.5146)
			(stroke
				(width 0.1524)
				(type default)
			)
			(layer "F.SilkS")
		)
		(fp_line
			(start -2.3876 2.5146)
			(end -1.6256 2.5146)
			(stroke
				(width 0.1524)
				(type default)
			)
			(layer "F.SilkS")
		)
		(fp_line
			(start -1.6256 -2.5146)
			(end -2.3876 -2.5146)
			(stroke
				(width 0.1524)
				(type default)
			)
			(layer "F.SilkS")
		)
		(fp_line
			(start -0.9906 -2.794)
			(end -0.9906 -2.286)
			(stroke
				(width 0.1524)
				(type default)
			)
			(layer "F.SilkS")
		)
		(fp_line
			(start 0.9906 2.286)
			(end 0.9906 3.048)
			(stroke
				(width 0.1524)
				(type default)
			)
			(layer "F.SilkS")
		)
		(fp_line
			(start 1.6256 2.5146)
			(end 2.3876 2.5146)
			(stroke
				(width 0.1524)
				(type default)
			)
			(layer "F.SilkS")
		)
		(fp_line
			(start 2.3876 2.5146)
			(end 2.3876 1.7526)
			(stroke
				(width 0.1524)
				(type default)
			)
			(layer "F.SilkS")
		)
		(fp_poly
			(pts
				(xy 1.6256 -2.5146) (xy 2.3876 -2.5146) (xy 2.3876 -1.7526)
			)
			(stroke
				(width 0)
				(type default)
			)
			(fill yes)
			(layer "F.SilkS")
		)
		(fp_rect
			(start -1.4986 1.4986)
			(end 1.4986 -1.4986)
			(stroke
				(width 0)
				(type default)
			)
			(fill no)
			(layer "F.CrtYd")
		)
		(fp_poly
			(pts
				(xy -2.3876 2.5146) (xy -2.3876 0.00254) (xy -1.4986 0.00254) (xy -1.4986 1.4986) (xy 1.4986 1.4986)
				(xy 1.4986 -1.4986) (xy -1.4986 -1.4986) (xy -1.4986 -0.00254) (xy -2.3876 -0.00254) (xy -2.3876 -2.5146)
				(xy 2.3876 -2.5146) (xy 2.3876 2.5146)
			)
			(stroke
				(width 0)
				(type default)
			)
			(fill no)
			(layer "F.CrtYd")
		)
		(fp_rect
			(start -2.3876 2.5146)
			(end 2.3876 -2.5146)
			(stroke
				(width 0)
				(type default)
			)
			(fill no)
			(layer "F.Fab")
		)
		(pad "1" smd rect
			(at 0.99949 -1.5494)
			(size 0.3048 0.9144)
			(layers "F.Cu" "F.Mask" "F.Paste")
			(net "P3V3_PWR")
		)
		(pad "2" smd rect
			(at 0.50038 -1.5494)
			(size 0.3048 0.9144)
			(layers "F.Cu" "F.Mask" "F.Paste")
			(net "P3V3_PWR")
		)
		(pad "3" smd rect
			(at 0 -1.5494)
			(size 0.3048 0.9144)
			(layers "F.Cu" "F.Mask" "F.Paste")
			(net "P1V8_PWR_GD")
		)
		(pad "4" smd rect
			(at -0.50038 -1.5494)
			(size 0.3048 0.9144)
			(layers "F.Cu" "F.Mask" "F.Paste")
			(net "P1V8_PWR_BIAS")
		)
		(pad "5" smd rect
			(at -0.99949 -1.5494)
			(size 0.3048 0.9144)
			(layers "F.Cu" "F.Mask" "F.Paste")
			(net "P1V8_PWR_EN_R")
		)
		(pad "6" smd rect
			(at -0.99949 1.5494)
			(size 0.3048 0.9144)
			(layers "F.Cu" "F.Mask" "F.Paste")
			(net "GND")
		)
		(pad "7" smd rect
			(at -0.50038 1.5494)
			(size 0.3048 0.9144)
			(layers "F.Cu" "F.Mask" "F.Paste")
			(net "P1V8_PWR_SS_C")
		)
		(pad "8" smd rect
			(at 0 1.5494)
			(size 0.3048 0.9144)
			(layers "F.Cu" "F.Mask" "F.Paste")
			(net "P1V8_PWR_FB")
		)
		(pad "9" smd rect
			(at 0.50038 1.5494)
			(size 0.3048 0.9144)
			(layers "F.Cu" "F.Mask" "F.Paste")
			(net "P1V8_PWR")
		)
		(pad "10" smd rect
			(at 0.99949 1.5494)
			(size 0.3048 0.9144)
			(layers "F.Cu" "F.Mask" "F.Paste")
			(net "P1V8_PWR")
		)
		(pad "11" smd custom
			(at 0 0)
			(size 0.4318 0.4318)
			(layers "F.Cu" "F.Mask" "F.Paste")
			(net "GND")
			(options
				(clearance outline)
				(anchor circle)
			)
			(primitives
				(gr_poly
					(pts
						(xy -1.2446 0.8636) (xy -1.2446 0.3937) (xy -1.8796 0.3937) (xy -1.8796 0.1143) (xy -1.2446 0.1143)
						(xy -1.2446 -0.1143) (xy -1.8796 -0.1143) (xy -1.8796 -0.3937) (xy -1.2446 -0.3937) (xy -1.2446 -0.8636)
						(xy 1.2446 -0.8636) (xy 1.2446 -0.3937) (xy 1.8796 -0.3937) (xy 1.8796 -0.1143) (xy 1.2446 -0.1143)
						(xy 1.2446 0.1143) (xy 1.8796 0.1143) (xy 1.8796 0.3937) (xy 1.2446 0.3937) (xy 1.2446 0.8636)
					)
					(width 0)
					(fill yes)
				)
			)
		)
	)
)
